(kicad_pcb
	(version 20260206)
	(generator "pcbnew")
	(generator_version "10.0")
	(general
		(thickness 1.6)
		(legacy_teardrops no)
	)
	(paper "A4")
	(title_block
		(title "01162023_DA0F0TEBIF0_F0T_Expander_BD_F_brd_V02_OCP.brd")
		(comment 1 "Grand Teton / footprints 2389-2394 of 9728")
	)
	(layers
		(0 "F.Cu" signal "TOP")
		(4 "In1.Cu" signal "GND")
		(6 "In2.Cu" signal "VCC")
		(8 "In3.Cu" signal "VCC1")
		(10 "In4.Cu" signal "GND1")
		(12 "In5.Cu" signal "IN1")
		(14 "In6.Cu" signal "GND2")
		(16 "In7.Cu" signal "IN2")
		(18 "In8.Cu" signal "GND3")
		(20 "In9.Cu" signal "IN3")
		(22 "In10.Cu" signal "GND4")
		(24 "In11.Cu" signal "IN4")
		(26 "In12.Cu" signal "GND5")
		(28 "In13.Cu" signal "IN5")
		(30 "In14.Cu" signal "GND6")
		(32 "In15.Cu" signal "IN6")
		(34 "In16.Cu" signal "GND7")
		(2 "B.Cu" signal "BOTTOM")
		(9 "F.Adhes" user "F.Adhesive")
		(11 "B.Adhes" user "B.Adhesive")
		(13 "F.Paste" user "Package Geometry/Pastemask Top")
		(15 "B.Paste" user "Package Geometry/Pastemask Bottom")
		(5 "F.SilkS" user "Ref Des/Silkscreen Top")
		(7 "B.SilkS" user "Ref Des/Silkscreen Bottom")
		(1 "F.Mask" user "Board Geometry/Soldermask Top")
		(3 "B.Mask" user "Board Geometry/Soldermask Bottom")
		(17 "Dwgs.User" user "User.Drawings")
		(19 "Cmts.User" user "User.Comments")
		(21 "Eco1.User" user "User.Eco1")
		(23 "Eco2.User" user "User.Eco2")
		(25 "Edge.Cuts" user "Board Geometry/Outline")
		(27 "Margin" user)
		(31 "F.CrtYd" user "Package Geometry/Place Bound Top")
		(29 "B.CrtYd" user "Package Geometry/Place Bound Bottom")
		(35 "F.Fab" user "Ref Des/Assembly Top")
		(33 "B.Fab" user "Ref Des/Assembly Bottom")
	)
	(footprint ""
		(layer "F.Cu")
		(at 337.566 -205.232 -90)
		(property "Reference" "R4123"
			(at 0 0 270)
			(layer "F.SilkS")
			(hide yes)
			(effects
				(font
					(size 1.27 1.27)
				)
			)
		)
		(property "Value" ""
			(at 0 0 270)
			(layer "F.Fab")
			(effects
				(font
					(size 1.27 1.27)
				)
			)
		)
		(duplicate_pad_numbers_are_jumpers no)
		(fp_line
			(start -0.7874 0.4064)
			(end -0.7874 -0.4064)
			(stroke
				(width 0.1524)
				(type default)
			)
			(layer "F.SilkS")
		)
		(fp_line
			(start 0.7874 0.4064)
			(end -0.7874 0.4064)
			(stroke
				(width 0.1524)
				(type default)
			)
			(layer "F.SilkS")
		)
		(fp_line
			(start -0.7874 -0.4064)
			(end 0.7874 -0.4064)
			(stroke
				(width 0.1524)
				(type default)
			)
			(layer "F.SilkS")
		)
		(fp_line
			(start 0.7874 -0.4064)
			(end 0.7874 0.4064)
			(stroke
				(width 0.1524)
				(type default)
			)
			(layer "F.SilkS")
		)
		(fp_line
			(start -0.67945 0.3048)
			(end -0.67945 -0.305054)
			(stroke
				(width 0.1)
				(type default)
			)
			(layer "F.Fab")
		)
		(fp_line
			(start -0.12065 0.3048)
			(end -0.67945 0.3048)
			(stroke
				(width 0.1)
				(type default)
			)
			(layer "F.Fab")
		)
		(fp_line
			(start 0.120396 0.3048)
			(end 0.120396 0.2794)
			(stroke
				(width 0.1)
				(type default)
			)
			(layer "F.Fab")
		)
		(fp_line
			(start 0.67945 0.3048)
			(end 0.120396 0.3048)
			(stroke
				(width 0.1)
				(type default)
			)
			(layer "F.Fab")
		)
		(fp_line
			(start -0.12065 0.2794)
			(end -0.12065 0.3048)
			(stroke
				(width 0.1)
				(type default)
			)
			(layer "F.Fab")
		)
		(fp_line
			(start 0.120396 0.2794)
			(end -0.12065 0.2794)
			(stroke
				(width 0.1)
				(type default)
			)
			(layer "F.Fab")
		)
		(fp_line
			(start -0.12065 -0.2794)
			(end 0.12065 -0.2794)
			(stroke
				(width 0.1)
				(type default)
			)
			(layer "F.Fab")
		)
		(fp_line
			(start 0.12065 -0.2794)
			(end 0.12065 -0.3048)
			(stroke
				(width 0.1)
				(type default)
			)
			(layer "F.Fab")
		)
		(fp_line
			(start 0.12065 -0.3048)
			(end 0.67945 -0.3048)
			(stroke
				(width 0.1)
				(type default)
			)
			(layer "F.Fab")
		)
		(fp_line
			(start 0.67945 -0.3048)
			(end 0.67945 0.3048)
			(stroke
				(width 0.1)
				(type default)
			)
			(layer "F.Fab")
		)
		(fp_line
			(start -0.67945 -0.305054)
			(end -0.12065 -0.305054)
			(stroke
				(width 0.1)
				(type default)
			)
			(layer "F.Fab")
		)
		(fp_line
			(start -0.12065 -0.305054)
			(end -0.12065 -0.2794)
			(stroke
				(width 0.1)
				(type default)
			)
			(layer "F.Fab")
		)
		(pad "1" smd circle
			(at -0.40005 0 270)
			(size 0 0)
			(layers "F.Cu" "F.Mask" "F.Paste")
			(net "SSD10_PWR_EN")
		)
		(pad "2" smd circle
			(at 0.40005 0 270)
			(size 0 0)
			(layers "F.Cu" "F.Mask" "F.Paste")
			(net "SSD10_PWR_EN_R")
		)
	)
	(footprint ""
		(layer "F.Cu")
		(at 189.047374 -19.33956)
		(property "Reference" "C3916"
			(at 0 0 0)
			(layer "F.SilkS")
			(hide yes)
			(effects
				(font
					(size 1.27 1.27)
				)
			)
		)
		(property "Value" ""
			(at 0 0 0)
			(layer "F.Fab")
			(effects
				(font
					(size 1.27 1.27)
				)
			)
		)
		(duplicate_pad_numbers_are_jumpers no)
		(fp_line
			(start -0.7874 -0.4064)
			(end 0.7874 -0.4064)
			(stroke
				(width 0.1524)
				(type default)
			)
			(layer "F.SilkS")
		)
		(fp_line
			(start -0.7874 0.4064)
			(end -0.7874 -0.4064)
			(stroke
				(width 0.1524)
				(type default)
			)
			(layer "F.SilkS")
		)
		(fp_line
			(start 0.7874 -0.4064)
			(end 0.7874 0.4064)
			(stroke
				(width 0.1524)
				(type default)
			)
			(layer "F.SilkS")
		)
		(fp_line
			(start 0.7874 0.4064)
			(end -0.7874 0.4064)
			(stroke
				(width 0.1524)
				(type default)
			)
			(layer "F.SilkS")
		)
		(fp_line
			(start -0.67945 -0.305054)
			(end -0.12065 -0.305054)
			(stroke
				(width 0.1)
				(type default)
			)
			(layer "F.Fab")
		)
		(fp_line
			(start -0.67945 0.3048)
			(end -0.67945 -0.305054)
			(stroke
				(width 0.1)
				(type default)
			)
			(layer "F.Fab")
		)
		(fp_line
			(start -0.12065 -0.305054)
			(end -0.12065 -0.2794)
			(stroke
				(width 0.1)
				(type default)
			)
			(layer "F.Fab")
		)
		(fp_line
			(start -0.12065 -0.2794)
			(end 0.12065 -0.2794)
			(stroke
				(width 0.1)
				(type default)
			)
			(layer "F.Fab")
		)
		(fp_line
			(start -0.12065 0.2794)
			(end -0.12065 0.3048)
			(stroke
				(width 0.1)
				(type default)
			)
			(layer "F.Fab")
		)
		(fp_line
			(start -0.12065 0.3048)
			(end -0.67945 0.3048)
			(stroke
				(width 0.1)
				(type default)
			)
			(layer "F.Fab")
		)
		(fp_line
			(start 0.120396 0.2794)
			(end -0.12065 0.2794)
			(stroke
				(width 0.1)
				(type default)
			)
			(layer "F.Fab")
		)
		(fp_line
			(start 0.120396 0.3048)
			(end 0.120396 0.2794)
			(stroke
				(width 0.1)
				(type default)
			)
			(layer "F.Fab")
		)
		(fp_line
			(start 0.12065 -0.3048)
			(end 0.67945 -0.3048)
			(stroke
				(width 0.1)
				(type default)
			)
			(layer "F.Fab")
		)
		(fp_line
			(start 0.12065 -0.2794)
			(end 0.12065 -0.3048)
			(stroke
				(width 0.1)
				(type default)
			)
			(layer "F.Fab")
		)
		(fp_line
			(start 0.67945 -0.3048)
			(end 0.67945 0.3048)
			(stroke
				(width 0.1)
				(type default)
			)
			(layer "F.Fab")
		)
		(fp_line
			(start 0.67945 0.3048)
			(end 0.120396 0.3048)
			(stroke
				(width 0.1)
				(type default)
			)
			(layer "F.Fab")
		)
		(pad "1" smd circle
			(at -0.40005 0)
			(size 0 0)
			(layers "F.Cu" "F.Mask" "F.Paste")
			(net "P12V_SSD6")
		)
		(pad "2" smd circle
			(at 0.40005 0)
			(size 0 0)
			(layers "F.Cu" "F.Mask" "F.Paste")
			(net "GND")
		)
	)
	(footprint ""
		(layer "F.Cu")
		(at 355.081586 -262.04672 180)
		(property "Reference" "PC129"
			(at 0 0 180)
			(layer "F.SilkS")
			(hide yes)
			(effects
				(font
					(size 1.27 1.27)
				)
			)
		)
		(property "Value" ""
			(at 0 0 180)
			(layer "F.Fab")
			(effects
				(font
					(size 1.27 1.27)
				)
			)
		)
		(duplicate_pad_numbers_are_jumpers no)
		(fp_line
			(start 0.7874 0.4064)
			(end -0.7874 0.4064)
			(stroke
				(width 0.1524)
				(type default)
			)
			(layer "F.SilkS")
		)
		(fp_line
			(start 0.7874 -0.4064)
			(end 0.7874 0.4064)
			(stroke
				(width 0.1524)
				(type default)
			)
			(layer "F.SilkS")
		)
		(fp_line
			(start -0.7874 0.4064)
			(end -0.7874 -0.4064)
			(stroke
				(width 0.1524)
				(type default)
			)
			(layer "F.SilkS")
		)
		(fp_line
			(start -0.7874 -0.4064)
			(end 0.7874 -0.4064)
			(stroke
				(width 0.1524)
				(type default)
			)
			(layer "F.SilkS")
		)
		(fp_line
			(start 0.67945 0.3048)
			(end 0.120396 0.3048)
			(stroke
				(width 0.1)
				(type default)
			)
			(layer "F.Fab")
		)
		(fp_line
			(start 0.67945 -0.3048)
			(end 0.67945 0.3048)
			(stroke
				(width 0.1)
				(type default)
			)
			(layer "F.Fab")
		)
		(fp_line
			(start 0.12065 -0.2794)
			(end 0.12065 -0.3048)
			(stroke
				(width 0.1)
				(type default)
			)
			(layer "F.Fab")
		)
		(fp_line
			(start 0.12065 -0.3048)
			(end 0.67945 -0.3048)
			(stroke
				(width 0.1)
				(type default)
			)
			(layer "F.Fab")
		)
		(fp_line
			(start 0.120396 0.3048)
			(end 0.120396 0.2794)
			(stroke
				(width 0.1)
				(type default)
			)
			(layer "F.Fab")
		)
		(fp_line
			(start 0.120396 0.2794)
			(end -0.12065 0.2794)
			(stroke
				(width 0.1)
				(type default)
			)
			(layer "F.Fab")
		)
		(fp_line
			(start -0.12065 0.3048)
			(end -0.67945 0.3048)
			(stroke
				(width 0.1)
				(type default)
			)
			(layer "F.Fab")
		)
		(fp_line
			(start -0.12065 0.2794)
			(end -0.12065 0.3048)
			(stroke
				(width 0.1)
				(type default)
			)
			(layer "F.Fab")
		)
		(fp_line
			(start -0.12065 -0.2794)
			(end 0.12065 -0.2794)
			(stroke
				(width 0.1)
				(type default)
			)
			(layer "F.Fab")
		)
		(fp_line
			(start -0.12065 -0.305054)
			(end -0.12065 -0.2794)
			(stroke
				(width 0.1)
				(type default)
			)
			(layer "F.Fab")
		)
		(fp_line
			(start -0.67945 0.3048)
			(end -0.67945 -0.305054)
			(stroke
				(width 0.1)
				(type default)
			)
			(layer "F.Fab")
		)
		(fp_line
			(start -0.67945 -0.305054)
			(end -0.12065 -0.305054)
			(stroke
				(width 0.1)
				(type default)
			)
			(layer "F.Fab")
		)
		(pad "1" smd circle
			(at -0.40005 0 180)
			(size 0 0)
			(layers "F.Cu" "F.Mask" "F.Paste")
			(net "P0V8_PEX2_VSEN2")
		)
		(pad "2" smd circle
			(at 0.40005 0 180)
			(size 0 0)
			(layers "F.Cu" "F.Mask" "F.Paste")
			(net "SH_P0V8_PEX2_RGND2")
		)
	)
	(footprint ""
		(layer "F.Cu")
		(at 106.385106 -380.098808 90)
		(property "Reference" "R6731"
			(at 0 0 90)
			(layer "F.SilkS")
			(hide yes)
			(effects
				(font
					(size 1.27 1.27)
				)
			)
		)
		(property "Value" ""
			(at 0 0 90)
			(layer "F.Fab")
			(effects
				(font
					(size 1.27 1.27)
				)
			)
		)
		(duplicate_pad_numbers_are_jumpers no)
		(fp_line
			(start 0.7874 -0.4064)
			(end 0.7874 0.4064)
			(stroke
				(width 0.1524)
				(type default)
			)
			(layer "F.SilkS")
		)
		(fp_line
			(start -0.7874 -0.4064)
			(end 0.03429 -0.4064)
			(stroke
				(width 0.1524)
				(type default)
			)
			(layer "F.SilkS")
		)
		(fp_line
			(start 0.7874 0.4064)
			(end -0.7874 0.4064)
			(stroke
				(width 0.1524)
				(type default)
			)
			(layer "F.SilkS")
		)
		(fp_line
			(start -0.12065 -0.305054)
			(end -0.12065 -0.2794)
			(stroke
				(width 0.1)
				(type default)
			)
			(layer "F.Fab")
		)
		(fp_line
			(start -0.67945 -0.305054)
			(end -0.12065 -0.305054)
			(stroke
				(width 0.1)
				(type default)
			)
			(layer "F.Fab")
		)
		(fp_line
			(start 0.67945 -0.3048)
			(end 0.67945 0.3048)
			(stroke
				(width 0.1)
				(type default)
			)
			(layer "F.Fab")
		)
		(fp_line
			(start 0.12065 -0.3048)
			(end 0.67945 -0.3048)
			(stroke
				(width 0.1)
				(type default)
			)
			(layer "F.Fab")
		)
		(fp_line
			(start 0.12065 -0.2794)
			(end 0.12065 -0.3048)
			(stroke
				(width 0.1)
				(type default)
			)
			(layer "F.Fab")
		)
		(fp_line
			(start -0.12065 -0.2794)
			(end 0.12065 -0.2794)
			(stroke
				(width 0.1)
				(type default)
			)
			(layer "F.Fab")
		)
		(fp_line
			(start 0.120396 0.2794)
			(end -0.12065 0.2794)
			(stroke
				(width 0.1)
				(type default)
			)
			(layer "F.Fab")
		)
		(fp_line
			(start -0.12065 0.2794)
			(end -0.12065 0.3048)
			(stroke
				(width 0.1)
				(type default)
			)
			(layer "F.Fab")
		)
		(fp_line
			(start 0.67945 0.3048)
			(end 0.120396 0.3048)
			(stroke
				(width 0.1)
				(type default)
			)
			(layer "F.Fab")
		)
		(fp_line
			(start 0.120396 0.3048)
			(end 0.120396 0.2794)
			(stroke
				(width 0.1)
				(type default)
			)
			(layer "F.Fab")
		)
		(fp_line
			(start -0.12065 0.3048)
			(end -0.67945 0.3048)
			(stroke
				(width 0.1)
				(type default)
			)
			(layer "F.Fab")
		)
		(fp_line
			(start -0.67945 0.3048)
			(end -0.67945 -0.305054)
			(stroke
				(width 0.1)
				(type default)
			)
			(layer "F.Fab")
		)
		(pad "1" smd rect
			(at -0.40005 0 270)
			(size 0.4572 0.508)
			(layers "F.Cu" "F.Mask" "F.Paste")
			(net "USB2_BIC_USB8042_DP")
		)
		(pad "2" smd rect
			(at 0.40005 0 270)
			(size 0.4572 0.508)
			(layers "F.Cu" "F.Mask" "F.Paste")
			(net "USB2_BIC_DP")
		)
	)
	(footprint ""
		(layer "F.Cu")
		(at 221.251272 -143.942562)
		(property "Reference" "R4206"
			(at 0 0 0)
			(layer "F.SilkS")
			(hide yes)
			(effects
				(font
					(size 1.27 1.27)
				)
			)
		)
		(property "Value" ""
			(at 0 0 0)
			(layer "F.Fab")
			(effects
				(font
					(size 1.27 1.27)
				)
			)
		)
		(duplicate_pad_numbers_are_jumpers no)
		(fp_line
			(start -0.7874 -0.4064)
			(end 0.7874 -0.4064)
			(stroke
				(width 0.1524)
				(type default)
			)
			(layer "F.SilkS")
		)
		(fp_line
			(start -0.7874 0.4064)
			(end -0.7874 -0.4064)
			(stroke
				(width 0.1524)
				(type default)
			)
			(layer "F.SilkS")
		)
		(fp_line
			(start 0.7874 -0.4064)
			(end 0.7874 0.4064)
			(stroke
				(width 0.1524)
				(type default)
			)
			(layer "F.SilkS")
		)
		(fp_line
			(start 0.7874 0.4064)
			(end -0.7874 0.4064)
			(stroke
				(width 0.1524)
				(type default)
			)
			(layer "F.SilkS")
		)
		(fp_line
			(start -0.67945 -0.305054)
			(end -0.12065 -0.305054)
			(stroke
				(width 0.1)
				(type default)
			)
			(layer "F.Fab")
		)
		(fp_line
			(start -0.67945 0.3048)
			(end -0.67945 -0.305054)
			(stroke
				(width 0.1)
				(type default)
			)
			(layer "F.Fab")
		)
		(fp_line
			(start -0.12065 -0.305054)
			(end -0.12065 -0.2794)
			(stroke
				(width 0.1)
				(type default)
			)
			(layer "F.Fab")
		)
		(fp_line
			(start -0.12065 -0.2794)
			(end 0.12065 -0.2794)
			(stroke
				(width 0.1)
				(type default)
			)
			(layer "F.Fab")
		)
		(fp_line
			(start -0.12065 0.2794)
			(end -0.12065 0.3048)
			(stroke
				(width 0.1)
				(type default)
			)
			(layer "F.Fab")
		)
		(fp_line
			(start -0.12065 0.3048)
			(end -0.67945 0.3048)
			(stroke
				(width 0.1)
				(type default)
			)
			(layer "F.Fab")
		)
		(fp_line
			(start 0.120396 0.2794)
			(end -0.12065 0.2794)
			(stroke
				(width 0.1)
				(type default)
			)
			(layer "F.Fab")
		)
		(fp_line
			(start 0.120396 0.3048)
			(end 0.120396 0.2794)
			(stroke
				(width 0.1)
				(type default)
			)
			(layer "F.Fab")
		)
		(fp_line
			(start 0.12065 -0.3048)
			(end 0.67945 -0.3048)
			(stroke
				(width 0.1)
				(type default)
			)
			(layer "F.Fab")
		)
		(fp_line
			(start 0.12065 -0.2794)
			(end 0.12065 -0.3048)
			(stroke
				(width 0.1)
				(type default)
			)
			(layer "F.Fab")
		)
		(fp_line
			(start 0.67945 -0.3048)
			(end 0.67945 0.3048)
			(stroke
				(width 0.1)
				(type default)
			)
			(layer "F.Fab")
		)
		(fp_line
			(start 0.67945 0.3048)
			(end 0.120396 0.3048)
			(stroke
				(width 0.1)
				(type default)
			)
			(layer "F.Fab")
		)
		(pad "1" smd circle
			(at -0.40005 0)
			(size 0 0)
			(layers "F.Cu" "F.Mask" "F.Paste")
			(net "GND")
		)
		(pad "2" smd circle
			(at 0.40005 0)
			(size 0 0)
			(layers "F.Cu" "F.Mask" "F.Paste")
			(net "PD_CK440_PEX_SBI_CLK")
		)
	)
	(footprint ""
		(layer "F.Cu")
		(at 357.965756 -232.457244)
		(property "Reference" "R4297"
			(at 0 0 0)
			(layer "F.SilkS")
			(hide yes)
			(effects
				(font
					(size 1.27 1.27)
				)
			)
		)
		(property "Value" ""
			(at 0 0 0)
			(layer "F.Fab")
			(effects
				(font
					(size 1.27 1.27)
				)
			)
		)
		(duplicate_pad_numbers_are_jumpers no)
		(fp_line
			(start -0.7874 -0.4064)
			(end 0.7874 -0.4064)
			(stroke
				(width 0.1524)
				(type default)
			)
			(layer "F.SilkS")
		)
		(fp_line
			(start -0.7874 0.4064)
			(end -0.7874 -0.4064)
			(stroke
				(width 0.1524)
				(type default)
			)
			(layer "F.SilkS")
		)
		(fp_line
			(start 0.7874 -0.4064)
			(end 0.7874 0.4064)
			(stroke
				(width 0.1524)
				(type default)
			)
			(layer "F.SilkS")
		)
		(fp_line
			(start 0.7874 0.4064)
			(end -0.7874 0.4064)
			(stroke
				(width 0.1524)
				(type default)
			)
			(layer "F.SilkS")
		)
		(fp_line
			(start -0.67945 -0.305054)
			(end -0.12065 -0.305054)
			(stroke
				(width 0.1)
				(type default)
			)
			(layer "F.Fab")
		)
		(fp_line
			(start -0.67945 0.3048)
			(end -0.67945 -0.305054)
			(stroke
				(width 0.1)
				(type default)
			)
			(layer "F.Fab")
		)
		(fp_line
			(start -0.12065 -0.305054)
			(end -0.12065 -0.2794)
			(stroke
				(width 0.1)
				(type default)
			)
			(layer "F.Fab")
		)
		(fp_line
			(start -0.12065 -0.2794)
			(end 0.12065 -0.2794)
			(stroke
				(width 0.1)
				(type default)
			)
			(layer "F.Fab")
		)
		(fp_line
			(start -0.12065 0.2794)
			(end -0.12065 0.3048)
			(stroke
				(width 0.1)
				(type default)
			)
			(layer "F.Fab")
		)
		(fp_line
			(start -0.12065 0.3048)
			(end -0.67945 0.3048)
			(stroke
				(width 0.1)
				(type default)
			)
			(layer "F.Fab")
		)
		(fp_line
			(start 0.120396 0.2794)
			(end -0.12065 0.2794)
			(stroke
				(width 0.1)
				(type default)
			)
			(layer "F.Fab")
		)
		(fp_line
			(start 0.120396 0.3048)
			(end 0.120396 0.2794)
			(stroke
				(width 0.1)
				(type default)
			)
			(layer "F.Fab")
		)
		(fp_line
			(start 0.12065 -0.3048)
			(end 0.67945 -0.3048)
			(stroke
				(width 0.1)
				(type default)
			)
			(layer "F.Fab")
		)
		(fp_line
			(start 0.12065 -0.2794)
			(end 0.12065 -0.3048)
			(stroke
				(width 0.1)
				(type default)
			)
			(layer "F.Fab")
		)
		(fp_line
			(start 0.67945 -0.3048)
			(end 0.67945 0.3048)
			(stroke
				(width 0.1)
				(type default)
			)
			(layer "F.Fab")
		)
		(fp_line
			(start 0.67945 0.3048)
			(end 0.120396 0.3048)
			(stroke
				(width 0.1)
				(type default)
			)
			(layer "F.Fab")
		)
		(pad "1" smd circle
			(at -0.40005 0)
			(size 0 0)
			(layers "F.Cu" "F.Mask" "F.Paste")
			(net "FPGA_JTAGENB")
		)
		(pad "2" smd circle
			(at 0.40005 0)
			(size 0 0)
			(layers "F.Cu" "F.Mask" "F.Paste")
			(net "GND")
		)
	)
)
